(kicad_pcb
	(version 20260206)
	(generator "pcbnew")
	(generator_version "10.0")
	(general
		(thickness 1.6)
		(legacy_teardrops no)
	)
	(paper "A4")
	(title_block
		(title "01162023_DA0F0TEBIF0_F0T_Expander_BD_F_brd_V02_OCP.brd")
		(comment 1 "Grand Teton / footprints 6819-6824 of 9728")
	)
	(layers
		(0 "F.Cu" signal "TOP")
		(4 "In1.Cu" signal "GND")
		(6 "In2.Cu" signal "VCC")
		(8 "In3.Cu" signal "VCC1")
		(10 "In4.Cu" signal "GND1")
		(12 "In5.Cu" signal "IN1")
		(14 "In6.Cu" signal "GND2")
		(16 "In7.Cu" signal "IN2")
		(18 "In8.Cu" signal "GND3")
		(20 "In9.Cu" signal "IN3")
		(22 "In10.Cu" signal "GND4")
		(24 "In11.Cu" signal "IN4")
		(26 "In12.Cu" signal "GND5")
		(28 "In13.Cu" signal "IN5")
		(30 "In14.Cu" signal "GND6")
		(32 "In15.Cu" signal "IN6")
		(34 "In16.Cu" signal "GND7")
		(2 "B.Cu" signal "BOTTOM")
		(9 "F.Adhes" user "F.Adhesive")
		(11 "B.Adhes" user "B.Adhesive")
		(13 "F.Paste" user "Package Geometry/Pastemask Top")
		(15 "B.Paste" user "Package Geometry/Pastemask Bottom")
		(5 "F.SilkS" user "Ref Des/Silkscreen Top")
		(7 "B.SilkS" user "Ref Des/Silkscreen Bottom")
		(1 "F.Mask" user "Board Geometry/Soldermask Top")
		(3 "B.Mask" user "Board Geometry/Soldermask Bottom")
		(17 "Dwgs.User" user "User.Drawings")
		(19 "Cmts.User" user "User.Comments")
		(21 "Eco1.User" user "User.Eco1")
		(23 "Eco2.User" user "User.Eco2")
		(25 "Edge.Cuts" user "Board Geometry/Outline")
		(27 "Margin" user)
		(31 "F.CrtYd" user "Package Geometry/Place Bound Top")
		(29 "B.CrtYd" user "Package Geometry/Place Bound Bottom")
		(35 "F.Fab" user "Ref Des/Assembly Top")
		(33 "B.Fab" user "Ref Des/Assembly Bottom")
	)
	(footprint ""
		(layer "F.Cu")
		(at 80.000602 -343.952322 90)
		(property "Reference" "C145"
			(at 0 0 90)
			(layer "F.SilkS")
			(hide yes)
			(effects
				(font
					(size 1.27 1.27)
				)
			)
		)
		(property "Value" ""
			(at 0 0 90)
			(layer "F.Fab")
			(effects
				(font
					(size 1.27 1.27)
				)
			)
		)
		(duplicate_pad_numbers_are_jumpers no)
		(fp_line
			(start 0.299974 -0.150114)
			(end 0.299974 0.150114)
			(stroke
				(width 0.1)
				(type default)
			)
			(layer "F.Fab")
		)
		(fp_line
			(start -0.299974 -0.150114)
			(end 0.299974 -0.150114)
			(stroke
				(width 0.1)
				(type default)
			)
			(layer "F.Fab")
		)
		(fp_line
			(start 0.299974 0.150114)
			(end -0.299974 0.150114)
			(stroke
				(width 0.1)
				(type default)
			)
			(layer "F.Fab")
		)
		(fp_line
			(start -0.299974 0.150114)
			(end -0.299974 -0.150114)
			(stroke
				(width 0.1)
				(type default)
			)
			(layer "F.Fab")
		)
		(pad "1" smd rect
			(at -0.2667 0 90)
			(size 0.3048 0.381)
			(layers "F.Cu" "F.Mask" "F.Paste")
			(net "P5E_PEX0_STN6_TX_DP<103>")
		)
		(pad "2" smd rect
			(at 0.2667 0 90)
			(size 0.3048 0.381)
			(layers "F.Cu" "F.Mask" "F.Paste")
			(net "P5E_PEX0_STN6_TX_C_DP<103>")
		)
	)
	(footprint ""
		(layer "F.Cu")
		(at 142.947644 -390.171686 -90)
		(property "Reference" "R4105"
			(at 0 0 270)
			(layer "F.SilkS")
			(hide yes)
			(effects
				(font
					(size 1.27 1.27)
				)
			)
		)
		(property "Value" ""
			(at 0 0 270)
			(layer "F.Fab")
			(effects
				(font
					(size 1.27 1.27)
				)
			)
		)
		(duplicate_pad_numbers_are_jumpers no)
		(fp_line
			(start -0.7874 0.4064)
			(end -0.7874 -0.4064)
			(stroke
				(width 0.1524)
				(type default)
			)
			(layer "F.SilkS")
		)
		(fp_line
			(start 0.7874 0.4064)
			(end -0.7874 0.4064)
			(stroke
				(width 0.1524)
				(type default)
			)
			(layer "F.SilkS")
		)
		(fp_line
			(start -0.7874 -0.4064)
			(end 0.7874 -0.4064)
			(stroke
				(width 0.1524)
				(type default)
			)
			(layer "F.SilkS")
		)
		(fp_line
			(start 0.7874 -0.4064)
			(end 0.7874 0.4064)
			(stroke
				(width 0.1524)
				(type default)
			)
			(layer "F.SilkS")
		)
		(fp_line
			(start -0.67945 0.3048)
			(end -0.67945 -0.305054)
			(stroke
				(width 0.1)
				(type default)
			)
			(layer "F.Fab")
		)
		(fp_line
			(start -0.12065 0.3048)
			(end -0.67945 0.3048)
			(stroke
				(width 0.1)
				(type default)
			)
			(layer "F.Fab")
		)
		(fp_line
			(start 0.120396 0.3048)
			(end 0.120396 0.2794)
			(stroke
				(width 0.1)
				(type default)
			)
			(layer "F.Fab")
		)
		(fp_line
			(start 0.67945 0.3048)
			(end 0.120396 0.3048)
			(stroke
				(width 0.1)
				(type default)
			)
			(layer "F.Fab")
		)
		(fp_line
			(start -0.12065 0.2794)
			(end -0.12065 0.3048)
			(stroke
				(width 0.1)
				(type default)
			)
			(layer "F.Fab")
		)
		(fp_line
			(start 0.120396 0.2794)
			(end -0.12065 0.2794)
			(stroke
				(width 0.1)
				(type default)
			)
			(layer "F.Fab")
		)
		(fp_line
			(start -0.12065 -0.2794)
			(end 0.12065 -0.2794)
			(stroke
				(width 0.1)
				(type default)
			)
			(layer "F.Fab")
		)
		(fp_line
			(start 0.12065 -0.2794)
			(end 0.12065 -0.3048)
			(stroke
				(width 0.1)
				(type default)
			)
			(layer "F.Fab")
		)
		(fp_line
			(start 0.12065 -0.3048)
			(end 0.67945 -0.3048)
			(stroke
				(width 0.1)
				(type default)
			)
			(layer "F.Fab")
		)
		(fp_line
			(start 0.67945 -0.3048)
			(end 0.67945 0.3048)
			(stroke
				(width 0.1)
				(type default)
			)
			(layer "F.Fab")
		)
		(fp_line
			(start -0.67945 -0.305054)
			(end -0.12065 -0.305054)
			(stroke
				(width 0.1)
				(type default)
			)
			(layer "F.Fab")
		)
		(fp_line
			(start -0.12065 -0.305054)
			(end -0.12065 -0.2794)
			(stroke
				(width 0.1)
				(type default)
			)
			(layer "F.Fab")
		)
		(pad "1" smd circle
			(at -0.40005 0 270)
			(size 0 0)
			(layers "F.Cu" "F.Mask" "F.Paste")
			(net "SMB_MB_BMC_SCL")
		)
		(pad "2" smd circle
			(at 0.40005 0 270)
			(size 0 0)
			(layers "F.Cu" "F.Mask" "F.Paste")
			(net "SMB_MB_BMC_R_SCL")
		)
	)
	(footprint ""
		(layer "F.Cu")
		(at 223.586294 -174.49038 180)
		(property "Reference" "R3147"
			(at 0 0 180)
			(layer "F.SilkS")
			(hide yes)
			(effects
				(font
					(size 1.27 1.27)
				)
			)
		)
		(property "Value" ""
			(at 0 0 180)
			(layer "F.Fab")
			(effects
				(font
					(size 1.27 1.27)
				)
			)
		)
		(duplicate_pad_numbers_are_jumpers no)
		(fp_line
			(start 0.7874 0.4064)
			(end -0.7874 0.4064)
			(stroke
				(width 0.1524)
				(type default)
			)
			(layer "F.SilkS")
		)
		(fp_line
			(start 0.7874 -0.4064)
			(end 0.7874 0.4064)
			(stroke
				(width 0.1524)
				(type default)
			)
			(layer "F.SilkS")
		)
		(fp_line
			(start -0.7874 0.4064)
			(end -0.7874 -0.4064)
			(stroke
				(width 0.1524)
				(type default)
			)
			(layer "F.SilkS")
		)
		(fp_line
			(start -0.7874 -0.4064)
			(end 0.7874 -0.4064)
			(stroke
				(width 0.1524)
				(type default)
			)
			(layer "F.SilkS")
		)
		(fp_line
			(start 0.67945 0.3048)
			(end 0.120396 0.3048)
			(stroke
				(width 0.1)
				(type default)
			)
			(layer "F.Fab")
		)
		(fp_line
			(start 0.67945 -0.3048)
			(end 0.67945 0.3048)
			(stroke
				(width 0.1)
				(type default)
			)
			(layer "F.Fab")
		)
		(fp_line
			(start 0.12065 -0.2794)
			(end 0.12065 -0.3048)
			(stroke
				(width 0.1)
				(type default)
			)
			(layer "F.Fab")
		)
		(fp_line
			(start 0.12065 -0.3048)
			(end 0.67945 -0.3048)
			(stroke
				(width 0.1)
				(type default)
			)
			(layer "F.Fab")
		)
		(fp_line
			(start 0.120396 0.3048)
			(end 0.120396 0.2794)
			(stroke
				(width 0.1)
				(type default)
			)
			(layer "F.Fab")
		)
		(fp_line
			(start 0.120396 0.2794)
			(end -0.12065 0.2794)
			(stroke
				(width 0.1)
				(type default)
			)
			(layer "F.Fab")
		)
		(fp_line
			(start -0.12065 0.3048)
			(end -0.67945 0.3048)
			(stroke
				(width 0.1)
				(type default)
			)
			(layer "F.Fab")
		)
		(fp_line
			(start -0.12065 0.2794)
			(end -0.12065 0.3048)
			(stroke
				(width 0.1)
				(type default)
			)
			(layer "F.Fab")
		)
		(fp_line
			(start -0.12065 -0.2794)
			(end 0.12065 -0.2794)
			(stroke
				(width 0.1)
				(type default)
			)
			(layer "F.Fab")
		)
		(fp_line
			(start -0.12065 -0.305054)
			(end -0.12065 -0.2794)
			(stroke
				(width 0.1)
				(type default)
			)
			(layer "F.Fab")
		)
		(fp_line
			(start -0.67945 0.3048)
			(end -0.67945 -0.305054)
			(stroke
				(width 0.1)
				(type default)
			)
			(layer "F.Fab")
		)
		(fp_line
			(start -0.67945 -0.305054)
			(end -0.12065 -0.305054)
			(stroke
				(width 0.1)
				(type default)
			)
			(layer "F.Fab")
		)
		(pad "1" smd circle
			(at -0.40005 0 180)
			(size 0 0)
			(layers "F.Cu" "F.Mask" "F.Paste")
			(net "ADM1085_IN")
		)
		(pad "2" smd circle
			(at 0.40005 0 180)
			(size 0 0)
			(layers "F.Cu" "F.Mask" "F.Paste")
			(net "GND")
		)
	)
	(footprint ""
		(layer "F.Cu")
		(at 393.669266 -82.642202 180)
		(property "Reference" "R1770"
			(at 0 0 180)
			(layer "F.SilkS")
			(hide yes)
			(effects
				(font
					(size 1.27 1.27)
				)
			)
		)
		(property "Value" ""
			(at 0 0 180)
			(layer "F.Fab")
			(effects
				(font
					(size 1.27 1.27)
				)
			)
		)
		(duplicate_pad_numbers_are_jumpers no)
		(fp_line
			(start 0.7874 0.4064)
			(end -0.7874 0.4064)
			(stroke
				(width 0.1524)
				(type default)
			)
			(layer "F.SilkS")
		)
		(fp_line
			(start 0.7874 -0.4064)
			(end 0.7874 0.4064)
			(stroke
				(width 0.1524)
				(type default)
			)
			(layer "F.SilkS")
		)
		(fp_line
			(start -0.7874 0.4064)
			(end -0.7874 -0.4064)
			(stroke
				(width 0.1524)
				(type default)
			)
			(layer "F.SilkS")
		)
		(fp_line
			(start -0.7874 -0.4064)
			(end 0.7874 -0.4064)
			(stroke
				(width 0.1524)
				(type default)
			)
			(layer "F.SilkS")
		)
		(fp_line
			(start 0.67945 0.3048)
			(end 0.120396 0.3048)
			(stroke
				(width 0.1)
				(type default)
			)
			(layer "F.Fab")
		)
		(fp_line
			(start 0.67945 -0.3048)
			(end 0.67945 0.3048)
			(stroke
				(width 0.1)
				(type default)
			)
			(layer "F.Fab")
		)
		(fp_line
			(start 0.12065 -0.2794)
			(end 0.12065 -0.3048)
			(stroke
				(width 0.1)
				(type default)
			)
			(layer "F.Fab")
		)
		(fp_line
			(start 0.12065 -0.3048)
			(end 0.67945 -0.3048)
			(stroke
				(width 0.1)
				(type default)
			)
			(layer "F.Fab")
		)
		(fp_line
			(start 0.120396 0.3048)
			(end 0.120396 0.2794)
			(stroke
				(width 0.1)
				(type default)
			)
			(layer "F.Fab")
		)
		(fp_line
			(start 0.120396 0.2794)
			(end -0.12065 0.2794)
			(stroke
				(width 0.1)
				(type default)
			)
			(layer "F.Fab")
		)
		(fp_line
			(start -0.12065 0.3048)
			(end -0.67945 0.3048)
			(stroke
				(width 0.1)
				(type default)
			)
			(layer "F.Fab")
		)
		(fp_line
			(start -0.12065 0.2794)
			(end -0.12065 0.3048)
			(stroke
				(width 0.1)
				(type default)
			)
			(layer "F.Fab")
		)
		(fp_line
			(start -0.12065 -0.2794)
			(end 0.12065 -0.2794)
			(stroke
				(width 0.1)
				(type default)
			)
			(layer "F.Fab")
		)
		(fp_line
			(start -0.12065 -0.305054)
			(end -0.12065 -0.2794)
			(stroke
				(width 0.1)
				(type default)
			)
			(layer "F.Fab")
		)
		(fp_line
			(start -0.67945 0.3048)
			(end -0.67945 -0.305054)
			(stroke
				(width 0.1)
				(type default)
			)
			(layer "F.Fab")
		)
		(fp_line
			(start -0.67945 -0.305054)
			(end -0.12065 -0.305054)
			(stroke
				(width 0.1)
				(type default)
			)
			(layer "F.Fab")
		)
		(pad "1" smd circle
			(at -0.40005 0 180)
			(size 0 0)
			(layers "F.Cu" "F.Mask" "F.Paste")
			(net "SMB_BIC_I2C6_MUX_CLK_R_SDA")
		)
		(pad "2" smd circle
			(at 0.40005 0 180)
			(size 0 0)
			(layers "F.Cu" "F.Mask" "F.Paste")
			(net "SMB_BIC_I2C6_MUX_CLK_SDA")
		)
	)
	(footprint ""
		(layer "F.Cu")
		(at 355.81463 -303.698402 90)
		(property "Reference" "PC201"
			(at 0 0 90)
			(layer "F.SilkS")
			(hide yes)
			(effects
				(font
					(size 1.27 1.27)
				)
			)
		)
		(property "Value" ""
			(at 0 0 90)
			(layer "F.Fab")
			(effects
				(font
					(size 1.27 1.27)
				)
			)
		)
		(duplicate_pad_numbers_are_jumpers no)
		(fp_line
			(start -4.53898 -2.150618)
			(end -4.539742 2.152142)
			(stroke
				(width 0.1524)
				(type default)
			)
			(layer "F.SilkS")
		)
		(fp_line
			(start -4.69138 -2.150618)
			(end -4.692396 2.161032)
			(stroke
				(width 0.1524)
				(type default)
			)
			(layer "F.SilkS")
		)
		(fp_line
			(start -4.84378 -2.150618)
			(end -4.53898 -2.150618)
			(stroke
				(width 0.1524)
				(type default)
			)
			(layer "F.SilkS")
		)
		(fp_line
			(start -4.84378 -2.150618)
			(end -4.842256 2.163064)
			(stroke
				(width 0.1524)
				(type default)
			)
			(layer "F.SilkS")
		)
		(fp_line
			(start 4.53898 -2.15011)
			(end 4.53898 2.15011)
			(stroke
				(width 0.1524)
				(type default)
			)
			(layer "F.SilkS")
		)
		(fp_line
			(start -4.53898 -2.15011)
			(end 4.53898 -2.15011)
			(stroke
				(width 0.1524)
				(type default)
			)
			(layer "F.SilkS")
		)
		(fp_line
			(start 4.53898 2.15011)
			(end -4.53898 2.15011)
			(stroke
				(width 0.1524)
				(type default)
			)
			(layer "F.SilkS")
		)
		(fp_line
			(start -4.53898 2.15011)
			(end -4.53898 -2.15011)
			(stroke
				(width 0.1524)
				(type default)
			)
			(layer "F.SilkS")
		)
		(fp_line
			(start -4.83108 2.150364)
			(end -4.447794 2.149348)
			(stroke
				(width 0.1524)
				(type default)
			)
			(layer "F.SilkS")
		)
		(fp_line
			(start 3.64998 -2.15011)
			(end 3.64998 2.15011)
			(stroke
				(width 0.1)
				(type default)
			)
			(layer "F.Fab")
		)
		(fp_line
			(start -3.64998 -2.15011)
			(end 3.64998 -2.15011)
			(stroke
				(width 0.1)
				(type default)
			)
			(layer "F.Fab")
		)
		(fp_line
			(start 3.64998 2.15011)
			(end -3.64998 2.15011)
			(stroke
				(width 0.1)
				(type default)
			)
			(layer "F.Fab")
		)
		(fp_line
			(start -3.64998 2.15011)
			(end -3.64998 -2.15011)
			(stroke
				(width 0.1)
				(type default)
			)
			(layer "F.Fab")
		)
		(fp_text user "-"
			(at 2.737866 -3.438398 90)
			(unlocked yes)
			(layer "F.SilkS")
			(effects
				(font
					(size 1.905 1.4224)
					(thickness 0.1524)
				)
				(justify left)
			)
		)
		(fp_text user "+"
			(at -4.899406 2.707132 90)
			(unlocked yes)
			(layer "F.SilkS")
			(effects
				(font
					(size 1.905 1.4224)
					(thickness 0.1524)
				)
				(justify left)
			)
		)
		(fp_text user "+"
			(at -6.214872 -0.337058 90)
			(unlocked yes)
			(layer "F.Fab")
			(effects
				(font
					(size 1.905 1.4224)
					(thickness 0.1524)
				)
				(justify left)
			)
		)
		(fp_text user "-"
			(at 4.313174 -0.094488 90)
			(unlocked yes)
			(layer "F.Fab")
			(effects
				(font
					(size 1.905 1.4224)
					(thickness 0.1524)
				)
				(justify left)
			)
		)
		(pad "1" smd rect
			(at -3.199892 0 90)
			(size 2.413 2.8194)
			(layers "F.Cu" "F.Mask" "F.Paste")
			(net "P0V8_PEX3")
		)
		(pad "2" smd rect
			(at 3.199892 0 90)
			(size 2.413 2.8194)
			(layers "F.Cu" "F.Mask" "F.Paste")
			(net "GND")
		)
	)
	(footprint ""
		(layer "F.Cu")
		(at 127.280162 -167.752014 180)
		(property "Reference" "R6661"
			(at 0 0 180)
			(layer "F.SilkS")
			(hide yes)
			(effects
				(font
					(size 1.27 1.27)
				)
			)
		)
		(property "Value" ""
			(at 0 0 180)
			(layer "F.Fab")
			(effects
				(font
					(size 1.27 1.27)
				)
			)
		)
		(duplicate_pad_numbers_are_jumpers no)
		(fp_line
			(start 0.7874 0.4064)
			(end -0.7874 0.4064)
			(stroke
				(width 0.1524)
				(type default)
			)
			(layer "F.SilkS")
		)
		(fp_line
			(start 0.7874 -0.4064)
			(end 0.7874 0.4064)
			(stroke
				(width 0.1524)
				(type default)
			)
			(layer "F.SilkS")
		)
		(fp_line
			(start -0.7874 0.4064)
			(end -0.7874 -0.4064)
			(stroke
				(width 0.1524)
				(type default)
			)
			(layer "F.SilkS")
		)
		(fp_line
			(start -0.7874 -0.4064)
			(end 0.7874 -0.4064)
			(stroke
				(width 0.1524)
				(type default)
			)
			(layer "F.SilkS")
		)
		(fp_line
			(start 0.67945 0.3048)
			(end 0.120396 0.3048)
			(stroke
				(width 0.1)
				(type default)
			)
			(layer "F.Fab")
		)
		(fp_line
			(start 0.67945 -0.3048)
			(end 0.67945 0.3048)
			(stroke
				(width 0.1)
				(type default)
			)
			(layer "F.Fab")
		)
		(fp_line
			(start 0.12065 -0.2794)
			(end 0.12065 -0.3048)
			(stroke
				(width 0.1)
				(type default)
			)
			(layer "F.Fab")
		)
		(fp_line
			(start 0.12065 -0.3048)
			(end 0.67945 -0.3048)
			(stroke
				(width 0.1)
				(type default)
			)
			(layer "F.Fab")
		)
		(fp_line
			(start 0.120396 0.3048)
			(end 0.120396 0.2794)
			(stroke
				(width 0.1)
				(type default)
			)
			(layer "F.Fab")
		)
		(fp_line
			(start 0.120396 0.2794)
			(end -0.12065 0.2794)
			(stroke
				(width 0.1)
				(type default)
			)
			(layer "F.Fab")
		)
		(fp_line
			(start -0.12065 0.3048)
			(end -0.67945 0.3048)
			(stroke
				(width 0.1)
				(type default)
			)
			(layer "F.Fab")
		)
		(fp_line
			(start -0.12065 0.2794)
			(end -0.12065 0.3048)
			(stroke
				(width 0.1)
				(type default)
			)
			(layer "F.Fab")
		)
		(fp_line
			(start -0.12065 -0.2794)
			(end 0.12065 -0.2794)
			(stroke
				(width 0.1)
				(type default)
			)
			(layer "F.Fab")
		)
		(fp_line
			(start -0.12065 -0.305054)
			(end -0.12065 -0.2794)
			(stroke
				(width 0.1)
				(type default)
			)
			(layer "F.Fab")
		)
		(fp_line
			(start -0.67945 0.3048)
			(end -0.67945 -0.305054)
			(stroke
				(width 0.1)
				(type default)
			)
			(layer "F.Fab")
		)
		(fp_line
			(start -0.67945 -0.305054)
			(end -0.12065 -0.305054)
			(stroke
				(width 0.1)
				(type default)
			)
			(layer "F.Fab")
		)
		(pad "1" smd circle
			(at -0.40005 0 180)
			(size 0 0)
			(layers "F.Cu" "F.Mask" "F.Paste")
			(net "NIC0_CLK_EN_BUF_N")
		)
		(pad "2" smd circle
			(at 0.40005 0 180)
			(size 0 0)
			(layers "F.Cu" "F.Mask" "F.Paste")
			(net "NIC0_CLK_EN_BUF_R_N")
		)
	)
)
